FILE_TYPE = CONNECTIVITY;
{Allegro Design Entry HDL 17.4-2019 S026 (4007227) 1/17/2022}
"PAGE_NUMBER" = 109;
0"NC";
END.
